(kicad_pcb
	(version 20260206)
	(generator "pcbnew")
	(generator_version "10.0")
	(general
		(thickness 1.6)
		(legacy_teardrops no)
	)
	(paper "A4")
	(title_block
		(title "Wiwynn_Tioga_Pass_MB.brd")
		(comment 1 "Tioga Pass / footprint 2254 of 4770 (U5D1), pads 1753-1862 of 3647")
	)
	(layers
		(0 "F.Cu" signal "TOP")
		(4 "In1.Cu" signal "L2GND")
		(6 "In2.Cu" signal "L3")
		(8 "In3.Cu" signal "L4GND")
		(10 "In4.Cu" signal "L5")
		(12 "In5.Cu" signal "L6GND")
		(14 "In6.Cu" signal "L7VCC")
		(16 "In7.Cu" signal "L8VCC")
		(18 "In8.Cu" signal "L9GND")
		(20 "In9.Cu" signal "L10")
		(22 "In10.Cu" signal "L11GND")
		(24 "In11.Cu" signal "L12")
		(26 "In12.Cu" signal "L13GND")
		(2 "B.Cu" signal "BOTTOM")
		(9 "F.Adhes" user "F.Adhesive")
		(11 "B.Adhes" user "B.Adhesive")
		(13 "F.Paste" user "Package Geometry/Pastemask Top")
		(15 "B.Paste" user "Package Geometry/Pastemask Bottom")
		(5 "F.SilkS" user "Ref Des/Silkscreen Top")
		(7 "B.SilkS" user "Ref Des/Silkscreen Bottom")
		(1 "F.Mask" user "Board Geometry/Soldermask Top")
		(3 "B.Mask" user "Board Geometry/Soldermask Bottom")
		(17 "Dwgs.User" user "User.Drawings")
		(19 "Cmts.User" user "User.Comments")
		(21 "Eco1.User" user "User.Eco1")
		(23 "Eco2.User" user "User.Eco2")
		(25 "Edge.Cuts" user "Board Geometry/Outline")
		(27 "Margin" user)
		(31 "F.CrtYd" user "Package Geometry/Place Bound Top")
		(29 "B.CrtYd" user "Package Geometry/Place Bound Bottom")
		(35 "F.Fab" user "Ref Des/Assembly Top")
		(33 "B.Fab" user "Ref Des/Assembly Bottom")
	)
	(footprint ""
		(layer "F.Cu")
		(at 270.000222 -76.550012 180)
		(property "Reference" "U5D1"
			(at 19.124422 31.601918 0)
			(unlocked yes)
			(layer "F.SilkS")
			(effects
				(font
					(size 0.7874 0.5842)
					(thickness 0.1524)
				)
			)
		)
		(property "Value" ""
			(at 0 0 180)
			(layer "F.Fab")
			(effects
				(font
					(size 1.27 1.27)
				)
			)
		)
		(duplicate_pad_numbers_are_jumpers no)
		(pad "CU10" smd circle
			(at -29.523944 12.539726)
			(size 0.4318 0.4318)
			(layers "F.Cu" "F.Mask" "F.Paste")
			(net "P3E_CPU0_PE3_OCP_RXP<15>")
		)
		(pad "CU12" smd circle
			(at -27.806904 12.539726)
			(size 0.4318 0.4318)
			(layers "F.Cu" "F.Mask" "F.Paste")
			(net "PVCCIO_CPU0")
		)
		(pad "CU14" smd circle
			(at -26.090118 12.539726)
			(size 0.4318 0.4318)
			(layers "F.Cu" "F.Mask" "F.Paste")
			(net "TP_CPU0_UPI2_RSVD_DD17")
		)
		(pad "CU18" smd circle
			(at -22.656038 12.539726)
			(size 0.4318 0.4318)
			(layers "F.Cu" "F.Mask" "F.Paste")
			(net "PVCCIO_CPU0")
		)
		(pad "CU20" smd circle
			(at -20.938998 12.539726)
			(size 0.4318 0.4318)
			(layers "F.Cu" "F.Mask" "F.Paste")
			(net "GND")
		)
		(pad "CU22" smd circle
			(at -19.221958 12.539726)
			(size 0.4318 0.4318)
			(layers "F.Cu" "F.Mask" "F.Paste")
			(net "GND")
		)
		(pad "CU24" smd circle
			(at -17.504918 12.539726)
			(size 0.4318 0.4318)
			(layers "F.Cu" "F.Mask" "F.Paste")
			(net "PVCCMCP_CPU0")
		)
		(pad "CU26" smd circle
			(at -15.787878 12.539726)
			(size 0.4318 0.4318)
			(layers "F.Cu" "F.Mask" "F.Paste")
			(net "CLK_100M_CPU0_BCLK2_DP")
		)
		(pad "CU28" smd circle
			(at -14.071092 12.539726)
			(size 0.4318 0.4318)
			(layers "F.Cu" "F.Mask" "F.Paste")
			(net "GND")
		)
		(pad "CU30" smd circle
			(at -12.354052 12.539726)
			(size 0.4318 0.4318)
			(layers "F.Cu" "F.Mask" "F.Paste")
			(net "GND")
		)
		(pad "CU32" smd circle
			(at -10.637012 12.539726)
			(size 0.4318 0.4318)
			(layers "F.Cu" "F.Mask" "F.Paste")
			(net "A_CPU0_MCP01_RBIAS")
		)
		(pad "CU34" smd circle
			(at -8.919972 12.539726)
			(size 0.4318 0.4318)
			(layers "F.Cu" "F.Mask" "F.Paste")
			(net "GND")
		)
		(pad "CU36" smd circle
			(at -7.202932 12.539726)
			(size 0.4318 0.4318)
			(layers "F.Cu" "F.Mask" "F.Paste")
			(net "GND")
		)
		(pad "CU38" smd circle
			(at -5.485892 12.539726)
			(size 0.4318 0.4318)
			(layers "F.Cu" "F.Mask" "F.Paste")
			(net "PVCCIN_CPU0")
		)
		(pad "CU40" smd circle
			(at -3.769106 12.539726)
			(size 0.4318 0.4318)
			(layers "F.Cu" "F.Mask" "F.Paste")
			(net "PVCCIN_CPU0")
		)
		(pad "CU42" smd circle
			(at -2.052066 12.539726)
			(size 0.4318 0.4318)
			(layers "F.Cu" "F.Mask" "F.Paste")
			(net "PVCCIN_CPU0")
		)
		(pad "CU52" smd circle
			(at 8.061452 10.739628)
			(size 0.508 0.508)
			(layers "F.Cu" "F.Mask" "F.Paste")
			(net "PVCCIN_CPU0")
		)
		(pad "CU54" smd circle
			(at 9.778492 10.739628)
			(size 0.4318 0.4318)
			(layers "F.Cu" "F.Mask" "F.Paste")
			(net "PVCCIN_CPU0")
		)
		(pad "CU56" smd circle
			(at 11.495532 10.739628)
			(size 0.4318 0.4318)
			(layers "F.Cu" "F.Mask" "F.Paste")
			(net "GND")
		)
		(pad "CU58" smd circle
			(at 13.212572 10.739628)
			(size 0.4318 0.4318)
			(layers "F.Cu" "F.Mask" "F.Paste")
			(net "PD_PIROM_CPU0_ADDR0")
		)
		(pad "CU60" smd circle
			(at 14.929612 10.739628)
			(size 0.4318 0.4318)
			(layers "F.Cu" "F.Mask" "F.Paste")
			(net "TP_CPU0_RSVD_66")
		)
		(pad "CU62" smd circle
			(at 16.646398 10.739628)
			(size 0.4318 0.4318)
			(layers "F.Cu" "F.Mask" "F.Paste")
			(net "GND")
		)
		(pad "CU64" smd circle
			(at 18.363438 10.739628)
			(size 0.4318 0.4318)
			(layers "F.Cu" "F.Mask" "F.Paste")
			(net "M_F_DQ<31>")
		)
		(pad "CU66" smd circle
			(at 20.080478 10.739628)
			(size 0.4318 0.4318)
			(layers "F.Cu" "F.Mask" "F.Paste")
			(net "M_F_DQ<25>")
		)
		(pad "CU68" smd circle
			(at 21.797518 10.739628)
			(size 0.4318 0.4318)
			(layers "F.Cu" "F.Mask" "F.Paste")
			(net "GND")
		)
		(pad "CU74" smd circle
			(at 26.948384 10.739628)
			(size 0.4318 0.4318)
			(layers "F.Cu" "F.Mask" "F.Paste")
			(net "M_F_DQS_DP<9>")
		)
		(pad "CU76" smd circle
			(at 28.665424 10.739628)
			(size 0.4318 0.4318)
			(layers "F.Cu" "F.Mask" "F.Paste")
			(net "GND")
		)
		(pad "CU78" smd circle
			(at 30.382464 10.739628)
			(size 0.4318 0.4318)
			(layers "F.Cu" "F.Mask" "F.Paste")
			(net "GND")
		)
		(pad "CU80" smd circle
			(at 32.099504 10.739628)
			(size 0.4318 0.4318)
			(layers "F.Cu" "F.Mask" "F.Paste")
			(net "GND")
		)
		(pad "CU82" smd circle
			(at 33.816544 10.739628)
			(size 0.4318 0.4318)
			(layers "F.Cu" "F.Mask" "F.Paste")
			(net "GND")
		)
		(pad "CU84" smd circle
			(at 35.533584 10.739628)
			(size 0.4318 0.4318)
			(layers "F.Cu" "F.Mask" "F.Paste")
			(net "M_D_DQS_DN<0>")
		)
		(pad "CU86" smd custom
			(at 37.250624 10.739628 270)
			(size 0.10795 0.10795)
			(layers "F.Cu" "F.Mask" "F.Paste")
			(net "GND")
			(options
				(clearance outline)
				(anchor circle)
			)
			(primitives
				(gr_poly
					(pts
						(arc
							(start 0.2159 -0.0381)
							(mid 0 -0.254)
							(end -0.2159 -0.0381)
						)
						(arc
							(start -0.2159 0.0381)
							(mid 0 0.254)
							(end 0.2159 0.0381)
						)
					)
					(width 0)
					(fill yes)
				)
			)
		)
		(pad "CV1" smd custom
			(at -37.250624 13.034772 90)
			(size 0.10795 0.10795)
			(layers "F.Cu" "F.Mask" "F.Paste")
			(net "GND")
			(options
				(clearance outline)
				(anchor circle)
			)
			(primitives
				(gr_poly
					(pts
						(arc
							(start 0.2159 -0.0381)
							(mid 0 -0.254)
							(end -0.2159 -0.0381)
						)
						(arc
							(start -0.2159 0.0381)
							(mid 0 0.254)
							(end 0.2159 0.0381)
						)
					)
					(width 0)
					(fill yes)
				)
			)
		)
		(pad "CV3" smd circle
			(at -35.533584 13.034772)
			(size 0.4318 0.4318)
			(layers "F.Cu" "F.Mask" "F.Paste")
			(net "P3E_CPU0_PE2_SS_TXN<1>")
		)
		(pad "CV5" smd circle
			(at -33.816544 13.034772)
			(size 0.4318 0.4318)
			(layers "F.Cu" "F.Mask" "F.Paste")
			(net "P3E_CPU0_PE3_OCP_TXP<15>")
		)
		(pad "CV7" smd circle
			(at -32.099504 13.034772)
			(size 0.4318 0.4318)
			(layers "F.Cu" "F.Mask" "F.Paste")
			(net "PVCCIO_CPU0")
		)
		(pad "CV9" smd circle
			(at -30.382464 13.034772)
			(size 0.4318 0.4318)
			(layers "F.Cu" "F.Mask" "F.Paste")
			(net "P3E_CPU0_PE3_OCP_RXN<15>")
		)
		(pad "CV11" smd circle
			(at -28.665424 13.034772)
			(size 0.4318 0.4318)
			(layers "F.Cu" "F.Mask" "F.Paste")
			(net "DMI_CPU0_PCH_RX_C_DP<3>")
		)
		(pad "CV13" smd circle
			(at -26.948384 13.034772)
			(size 0.4318 0.4318)
			(layers "F.Cu" "F.Mask" "F.Paste")
			(net "TP_CPU0_UPI2_RSVD_DD15")
		)
		(pad "CV17" smd circle
			(at -23.514558 13.034772)
			(size 0.4318 0.4318)
			(layers "F.Cu" "F.Mask" "F.Paste")
			(net "GND")
		)
		(pad "CV19" smd circle
			(at -21.797518 13.034772)
			(size 0.4318 0.4318)
			(layers "F.Cu" "F.Mask" "F.Paste")
			(net "GND")
		)
		(pad "CV21" smd circle
			(at -20.080478 13.034772)
			(size 0.4318 0.4318)
			(layers "F.Cu" "F.Mask" "F.Paste")
			(net "PVCCIO_CPU0")
		)
		(pad "CV23" smd circle
			(at -18.363438 13.034772)
			(size 0.4318 0.4318)
			(layers "F.Cu" "F.Mask" "F.Paste")
			(net "PVCCMCP_CPU0")
		)
		(pad "CV25" smd circle
			(at -16.646398 13.034772)
			(size 0.4318 0.4318)
			(layers "F.Cu" "F.Mask" "F.Paste")
			(net "GND")
		)
		(pad "CV27" smd circle
			(at -14.929612 13.034772)
			(size 0.4318 0.4318)
			(layers "F.Cu" "F.Mask" "F.Paste")
			(net "GND")
		)
		(pad "CV29" smd circle
			(at -13.212572 13.034772)
			(size 0.4318 0.4318)
			(layers "F.Cu" "F.Mask" "F.Paste")
			(net "M_F_DQS_DP<16>")
		)
		(pad "CV31" smd circle
			(at -11.495532 13.034772)
			(size 0.4318 0.4318)
			(layers "F.Cu" "F.Mask" "F.Paste")
			(net "GND")
		)
		(pad "CV33" smd circle
			(at -9.778492 13.034772)
			(size 0.4318 0.4318)
			(layers "F.Cu" "F.Mask" "F.Paste")
			(net "GND")
		)
		(pad "CV35" smd circle
			(at -8.061452 13.034772)
			(size 0.4318 0.4318)
			(layers "F.Cu" "F.Mask" "F.Paste")
			(net "M_F_DQS_DP<15>")
		)
		(pad "CV37" smd circle
			(at -6.344412 13.034772)
			(size 0.4318 0.4318)
			(layers "F.Cu" "F.Mask" "F.Paste")
			(net "GND")
		)
		(pad "CV39" smd circle
			(at -4.627626 13.034772)
			(size 0.4318 0.4318)
			(layers "F.Cu" "F.Mask" "F.Paste")
			(net "GND")
		)
		(pad "CV41" smd circle
			(at -2.910586 13.034772)
			(size 0.4318 0.4318)
			(layers "F.Cu" "F.Mask" "F.Paste")
			(net "GND")
		)
		(pad "CV51" smd circle
			(at 7.202932 11.234674)
			(size 0.508 0.508)
			(layers "F.Cu" "F.Mask" "F.Paste")
			(net "PVCCIN_CPU0")
		)
		(pad "CV53" smd circle
			(at 8.919972 11.234674)
			(size 0.4318 0.4318)
			(layers "F.Cu" "F.Mask" "F.Paste")
			(net "GND")
		)
		(pad "CV55" smd circle
			(at 10.637012 11.234674)
			(size 0.4318 0.4318)
			(layers "F.Cu" "F.Mask" "F.Paste")
			(net "GND")
		)
		(pad "CV57" smd circle
			(at 12.354052 11.234674)
			(size 0.4318 0.4318)
			(layers "F.Cu" "F.Mask" "F.Paste")
			(net "PD_PIROM_CPU0_ADDR1")
		)
		(pad "CV59" smd circle
			(at 14.071092 11.234674)
			(size 0.4318 0.4318)
			(layers "F.Cu" "F.Mask" "F.Paste")
			(net "FM_CPU0_SM_WP")
		)
		(pad "CV61" smd circle
			(at 15.787878 11.234674)
			(size 0.4318 0.4318)
			(layers "F.Cu" "F.Mask" "F.Paste")
			(net "M_F_CPU_VREF")
		)
		(pad "CV63" smd circle
			(at 17.504918 11.234674)
			(size 0.4318 0.4318)
			(layers "F.Cu" "F.Mask" "F.Paste")
			(net "GND")
		)
		(pad "CV65" smd circle
			(at 19.221958 11.234674)
			(size 0.4318 0.4318)
			(layers "F.Cu" "F.Mask" "F.Paste")
			(net "M_F_DQS_DN<3>")
		)
		(pad "CV67" smd circle
			(at 20.938998 11.234674)
			(size 0.4318 0.4318)
			(layers "F.Cu" "F.Mask" "F.Paste")
			(net "GND")
		)
		(pad "CV69" smd circle
			(at 22.656038 11.234674)
			(size 0.4318 0.4318)
			(layers "F.Cu" "F.Mask" "F.Paste")
			(net "TP_CPU0_RSVD_64")
		)
		(pad "CV73" smd circle
			(at 26.090118 11.234674)
			(size 0.4318 0.4318)
			(layers "F.Cu" "F.Mask" "F.Paste")
			(net "GND")
		)
		(pad "CV75" smd circle
			(at 27.806904 11.234674)
			(size 0.4318 0.4318)
			(layers "F.Cu" "F.Mask" "F.Paste")
			(net "M_F_DQ<6>")
		)
		(pad "CV77" smd circle
			(at 29.523944 11.234674)
			(size 0.4318 0.4318)
			(layers "F.Cu" "F.Mask" "F.Paste")
			(net "M_F_DQ<3>")
		)
		(pad "CV79" smd circle
			(at 31.240984 11.234674)
			(size 0.4318 0.4318)
			(layers "F.Cu" "F.Mask" "F.Paste")
			(net "GND")
		)
		(pad "CV81" smd circle
			(at 32.958024 11.234674)
			(size 0.4318 0.4318)
			(layers "F.Cu" "F.Mask" "F.Paste")
			(net "GND")
		)
		(pad "CV83" smd circle
			(at 34.675064 11.234674)
			(size 0.4318 0.4318)
			(layers "F.Cu" "F.Mask" "F.Paste")
			(net "GND")
		)
		(pad "CV85" smd circle
			(at 36.392104 11.234674)
			(size 0.4318 0.4318)
			(layers "F.Cu" "F.Mask" "F.Paste")
			(net "M_D_DQS_DP<0>")
		)
		(pad "CW2" smd circle
			(at -36.392104 13.530326)
			(size 0.4318 0.4318)
			(layers "F.Cu" "F.Mask" "F.Paste")
			(net "P3E_CPU0_PE1_SS_TXP<0>")
		)
		(pad "CW4" smd circle
			(at -34.675064 13.530326)
			(size 0.4318 0.4318)
			(layers "F.Cu" "F.Mask" "F.Paste")
			(net "P3E_CPU0_PE2_SS_TXP<0>")
		)
		(pad "CW6" smd circle
			(at -32.958024 13.530326)
			(size 0.4318 0.4318)
			(layers "F.Cu" "F.Mask" "F.Paste")
			(net "GND")
		)
		(pad "CW8" smd circle
			(at -31.240984 13.530326)
			(size 0.4318 0.4318)
			(layers "F.Cu" "F.Mask" "F.Paste")
			(net "P3E_CPU0_PE1_SS_RXN<0>")
		)
		(pad "CW10" smd circle
			(at -29.523944 13.530326)
			(size 0.4318 0.4318)
			(layers "F.Cu" "F.Mask" "F.Paste")
			(net "P3E_CPU0_PE3_OCP_RXP<14>")
		)
		(pad "CW12" smd circle
			(at -27.806904 13.530326)
			(size 0.4318 0.4318)
			(layers "F.Cu" "F.Mask" "F.Paste")
			(net "GND")
		)
		(pad "CW14" smd circle
			(at -26.090118 13.530326)
			(size 0.4318 0.4318)
			(layers "F.Cu" "F.Mask" "F.Paste")
			(net "TP_CPU0_UPI2_RSVD_DF15")
		)
		(pad "CW16" smd circle
			(at -24.373078 13.530326)
			(size 0.4318 0.4318)
			(layers "F.Cu" "F.Mask" "F.Paste")
			(net "TP_CPU0_UPI2_RSVD_DB15")
		)
		(pad "CW18" smd circle
			(at -22.656038 13.530326)
			(size 0.4318 0.4318)
			(layers "F.Cu" "F.Mask" "F.Paste")
			(net "GND")
		)
		(pad "CW20" smd circle
			(at -20.938998 13.530326)
			(size 0.4318 0.4318)
			(layers "F.Cu" "F.Mask" "F.Paste")
			(net "GND")
		)
		(pad "CW22" smd circle
			(at -19.221958 13.530326)
			(size 0.4318 0.4318)
			(layers "F.Cu" "F.Mask" "F.Paste")
			(net "TP_CPU0_KTI2_DFX_DN")
		)
		(pad "CW24" smd circle
			(at -17.504918 13.530326)
			(size 0.4318 0.4318)
			(layers "F.Cu" "F.Mask" "F.Paste")
			(net "PVCCMCP_CPU0")
		)
		(pad "CW26" smd circle
			(at -15.787878 13.530326)
			(size 0.4318 0.4318)
			(layers "F.Cu" "F.Mask" "F.Paste")
			(net "GND")
		)
		(pad "CW28" smd circle
			(at -14.071092 13.530326)
			(size 0.4318 0.4318)
			(layers "F.Cu" "F.Mask" "F.Paste")
			(net "M_F_DQ<62>")
		)
		(pad "CW30" smd circle
			(at -12.354052 13.530326)
			(size 0.4318 0.4318)
			(layers "F.Cu" "F.Mask" "F.Paste")
			(net "M_F_DQ<56>")
		)
		(pad "CW32" smd circle
			(at -10.637012 13.530326)
			(size 0.4318 0.4318)
			(layers "F.Cu" "F.Mask" "F.Paste")
			(net "GND")
		)
		(pad "CW34" smd circle
			(at -8.919972 13.530326)
			(size 0.4318 0.4318)
			(layers "F.Cu" "F.Mask" "F.Paste")
			(net "M_F_DQ<54>")
		)
		(pad "CW36" smd circle
			(at -7.202932 13.530326)
			(size 0.4318 0.4318)
			(layers "F.Cu" "F.Mask" "F.Paste")
			(net "M_F_DQ<48>")
		)
		(pad "CW38" smd circle
			(at -5.485892 13.530326)
			(size 0.4318 0.4318)
			(layers "F.Cu" "F.Mask" "F.Paste")
			(net "GND")
		)
		(pad "CW40" smd circle
			(at -3.769106 13.530326)
			(size 0.4318 0.4318)
			(layers "F.Cu" "F.Mask" "F.Paste")
			(net "GND")
		)
		(pad "CW42" smd circle
			(at -2.052066 13.530326)
			(size 0.4318 0.4318)
			(layers "F.Cu" "F.Mask" "F.Paste")
			(net "GND")
		)
		(pad "CW46" smd circle
			(at 2.910586 11.730228)
			(size 0.508 0.508)
			(layers "F.Cu" "F.Mask" "F.Paste")
			(net "PVCCIN_CPU0")
		)
		(pad "CW48" smd circle
			(at 4.627626 11.730228)
			(size 0.508 0.508)
			(layers "F.Cu" "F.Mask" "F.Paste")
			(net "PVCCIN_CPU0")
		)
		(pad "CW50" smd circle
			(at 6.344412 11.730228)
			(size 0.508 0.508)
			(layers "F.Cu" "F.Mask" "F.Paste")
			(net "PVCCIN_CPU0")
		)
		(pad "CW52" smd circle
			(at 8.061452 11.730228)
			(size 0.4318 0.4318)
			(layers "F.Cu" "F.Mask" "F.Paste")
			(net "GND")
		)
		(pad "CW54" smd circle
			(at 9.778492 11.730228)
			(size 0.4318 0.4318)
			(layers "F.Cu" "F.Mask" "F.Paste")
			(net "GND")
		)
		(pad "CW56" smd circle
			(at 11.495532 11.730228)
			(size 0.4318 0.4318)
			(layers "F.Cu" "F.Mask" "F.Paste")
			(net "PD_PIROM_CPU0_ADDR2")
		)
		(pad "CW58" smd circle
			(at 13.212572 11.730228)
			(size 0.4318 0.4318)
			(layers "F.Cu" "F.Mask" "F.Paste")
			(net "SMB_PIROM_CPU0_SDA")
		)
		(pad "CW60" smd circle
			(at 14.929612 11.730228)
			(size 0.4318 0.4318)
			(layers "F.Cu" "F.Mask" "F.Paste")
			(net "TP_CPU0_RSVD_61")
		)
		(pad "CW62" smd circle
			(at 16.646398 11.730228)
			(size 0.4318 0.4318)
			(layers "F.Cu" "F.Mask" "F.Paste")
			(net "TP_CPU0_RSVD_60")
		)
		(pad "CW64" smd circle
			(at 18.363438 11.730228)
			(size 0.4318 0.4318)
			(layers "F.Cu" "F.Mask" "F.Paste")
			(net "GND")
		)
		(pad "CW66" smd circle
			(at 20.080478 11.730228)
			(size 0.4318 0.4318)
			(layers "F.Cu" "F.Mask" "F.Paste")
			(net "GND")
		)
		(pad "CW68" smd circle
			(at 21.797518 11.730228)
			(size 0.4318 0.4318)
			(layers "F.Cu" "F.Mask" "F.Paste")
			(net "GND")
		)
		(pad "CW72" smd circle
			(at 25.231598 11.730228)
			(size 0.4318 0.4318)
			(layers "F.Cu" "F.Mask" "F.Paste")
			(net "FM_CPU0_PKGID1")
		)
		(pad "CW74" smd circle
			(at 26.948384 11.730228)
			(size 0.4318 0.4318)
			(layers "F.Cu" "F.Mask" "F.Paste")
			(net "GND")
		)
		(pad "CW76" smd circle
			(at 28.665424 11.730228)
			(size 0.4318 0.4318)
			(layers "F.Cu" "F.Mask" "F.Paste")
			(net "M_F_DQ<2>")
		)
		(pad "CW78" smd circle
			(at 30.382464 11.730228)
			(size 0.4318 0.4318)
			(layers "F.Cu" "F.Mask" "F.Paste")
			(net "GND")
		)
		(pad "CW80" smd circle
			(at 32.099504 11.730228)
			(size 0.4318 0.4318)
			(layers "F.Cu" "F.Mask" "F.Paste")
			(net "M_E_DQ<13>")
		)
		(pad "CW82" smd circle
			(at 33.816544 11.730228)
			(size 0.4318 0.4318)
			(layers "F.Cu" "F.Mask" "F.Paste")
			(net "GND")
		)
		(pad "CW84" smd circle
			(at 35.533584 11.730228)
			(size 0.4318 0.4318)
			(layers "F.Cu" "F.Mask" "F.Paste")
			(net "M_D_DQ<7>")
		)
		(pad "CW86" smd custom
			(at 37.250624 11.730228 270)
			(size 0.10795 0.10795)
			(layers "F.Cu" "F.Mask" "F.Paste")
			(net "M_D_DQ<6>")
			(options
				(clearance outline)
				(anchor circle)
			)
			(primitives
				(gr_poly
					(pts
						(arc
							(start 0.2159 -0.0381)
							(mid 0 -0.254)
							(end -0.2159 -0.0381)
						)
						(arc
							(start -0.2159 0.0381)
							(mid 0 0.254)
							(end 0.2159 0.0381)
						)
					)
					(width 0)
					(fill yes)
				)
			)
		)
	)
)
